(kicad_pcb
	(version 20260206)
	(generator "pcbnew")
	(generator_version "10.0")
	(general
		(thickness 1.6)
		(legacy_teardrops no)
	)
	(paper "A4")
	(title_block
		(title "baseboard — 13948-1b.1110WZS1818.brd")
		(comment 1 "Honey Badger (Wiwynn) / footprints 26-34 of 2523")
	)
	(layers
		(0 "F.Cu" signal "TOP")
		(4 "In1.Cu" signal "L2GND")
		(6 "In2.Cu" signal "L3")
		(8 "In3.Cu" signal "L4VCC")
		(10 "In4.Cu" signal "L5VCC")
		(12 "In5.Cu" signal "L6")
		(14 "In6.Cu" signal "L7GND")
		(2 "B.Cu" signal "BOTTOM")
		(9 "F.Adhes" user "F.Adhesive")
		(11 "B.Adhes" user "B.Adhesive")
		(13 "F.Paste" user "Package Geometry/Pastemask Top")
		(15 "B.Paste" user "Package Geometry/Pastemask Bottom")
		(5 "F.SilkS" user "Ref Des/Silkscreen Top")
		(7 "B.SilkS" user "Ref Des/Silkscreen Bottom")
		(1 "F.Mask" user "Board Geometry/Soldermask Top")
		(3 "B.Mask" user "Board Geometry/Soldermask Bottom")
		(17 "Dwgs.User" user "User.Drawings")
		(19 "Cmts.User" user "User.Comments")
		(21 "Eco1.User" user "User.Eco1")
		(23 "Eco2.User" user "User.Eco2")
		(25 "Edge.Cuts" user "Board Geometry/Outline")
		(27 "Margin" user)
		(31 "F.CrtYd" user "Package Geometry/Place Bound Top")
		(29 "B.CrtYd" user "Package Geometry/Place Bound Bottom")
		(35 "F.Fab" user "Ref Des/Assembly Top")
		(33 "B.Fab" user "Ref Des/Assembly Bottom")
	)
	(footprint ""
		(layer "F.Cu")
		(at 152.247092 -104.550464 -90)
		(property "Reference" "SL18"
			(at 0 0 270)
			(layer "F.SilkS")
			(hide yes)
			(effects
				(font
					(size 1.27 1.27)
				)
			)
		)
		(property "Value" "MPZ2012S300AT-GP"
			(at 0 -4.2418 270)
			(unlocked yes)
			(layer "F.Fab")
			(hide yes)
			(effects
				(font
					(size 1.016 1.016)
					(thickness 0.1524)
				)
			)
		)
		(property "Device Type" "L805H42"
			(at 0 -5.7912 270)
			(unlocked yes)
			(layer "F.Fab")
			(hide yes)
			(effects
				(font
					(size 1.016 1.016)
					(thickness 0.1524)
				)
			)
		)
		(duplicate_pad_numbers_are_jumpers no)
		(fp_line
			(start -0.889 1.7018)
			(end -0.889 -1.7018)
			(stroke
				(width 0.1524)
				(type default)
			)
			(layer "F.SilkS")
		)
		(fp_line
			(start 0.889 1.7018)
			(end -0.889 1.7018)
			(stroke
				(width 0.1524)
				(type default)
			)
			(layer "F.SilkS")
		)
		(fp_line
			(start -0.889 -1.7018)
			(end 0.889 -1.7018)
			(stroke
				(width 0.1524)
				(type default)
			)
			(layer "F.SilkS")
		)
		(fp_line
			(start 0.889 -1.7018)
			(end 0.889 1.7018)
			(stroke
				(width 0.1524)
				(type default)
			)
			(layer "F.SilkS")
		)
		(fp_rect
			(start -0.9652 1.778)
			(end 0.9652 -1.778)
			(stroke
				(width 0)
				(type default)
			)
			(fill no)
			(layer "F.CrtYd")
		)
		(fp_rect
			(start -0.9652 1.778)
			(end 0.9652 -1.778)
			(stroke
				(width 0)
				(type default)
			)
			(fill no)
			(layer "F.Fab")
		)
		(pad "1" smd rect
			(at 0 -0.9652 270)
			(size 1.397 1.143)
			(layers "F.Cu" "F.Mask" "F.Paste")
			(net "P0V9_E")
		)
		(pad "2" smd rect
			(at 0 0.9652 270)
			(size 1.397 1.143)
			(layers "F.Cu" "F.Mask" "F.Paste")
			(net "GB_VDDA")
		)
	)
	(footprint ""
		(layer "F.Cu")
		(at 257.483864 -228.210872 -90)
		(property "Reference" "PC101"
			(at 0 0 270)
			(layer "F.SilkS")
			(hide yes)
			(effects
				(font
					(size 1.27 1.27)
				)
			)
		)
		(property "Value" "SCD1U16V2KX-3GP"
			(at 1.1811 -2.7051 270)
			(unlocked yes)
			(layer "F.Fab")
			(hide yes)
			(effects
				(font
					(size 1.016 1.016)
					(thickness 0.1524)
				)
			)
		)
		(property "Device Type" "C402H22"
			(at 1.1811 -4.2291 270)
			(unlocked yes)
			(layer "F.Fab")
			(hide yes)
			(effects
				(font
					(size 1.016 1.016)
					(thickness 0.1524)
				)
			)
		)
		(duplicate_pad_numbers_are_jumpers no)
		(fp_rect
			(start -0.4318 0.9525)
			(end 0.4318 -0.9525)
			(stroke
				(width 0)
				(type default)
			)
			(fill no)
			(layer "F.CrtYd")
		)
		(fp_rect
			(start -0.4318 0.9525)
			(end 0.4318 -0.9525)
			(stroke
				(width 0)
				(type default)
			)
			(fill no)
			(layer "F.Fab")
		)
		(pad "1" smd custom
			(at 0 -0.4445 270)
			(size 0.1524 0.1524)
			(layers "F.Cu" "F.Mask" "F.Paste")
			(net "TPS74801_1V26_STBY_EN")
			(options
				(clearance outline)
				(anchor circle)
			)
			(primitives
				(gr_poly
					(pts
						(arc
							(start 0.3048 -0.2032)
							(mid 0.275042 -0.275042)
							(end 0.2032 -0.3048)
						)
						(arc
							(start -0.2032 -0.3048)
							(mid -0.275042 -0.275042)
							(end -0.3048 -0.2032)
						)
						(arc
							(start -0.3048 0.2032)
							(mid -0.275042 0.275042)
							(end -0.2032 0.3048)
						)
						(arc
							(start 0.2032 0.3048)
							(mid 0.275042 0.275042)
							(end 0.3048 0.2032)
						)
					)
					(width 0)
					(fill yes)
				)
			)
		)
		(pad "2" smd custom
			(at 0 0.4445 270)
			(size 0.1524 0.1524)
			(layers "F.Cu" "F.Mask" "F.Paste")
			(net "GND")
			(options
				(clearance outline)
				(anchor circle)
			)
			(primitives
				(gr_poly
					(pts
						(arc
							(start 0.3048 -0.2032)
							(mid 0.275042 -0.275042)
							(end 0.2032 -0.3048)
						)
						(arc
							(start -0.2032 -0.3048)
							(mid -0.275042 -0.275042)
							(end -0.3048 -0.2032)
						)
						(arc
							(start -0.3048 0.2032)
							(mid -0.275042 0.275042)
							(end -0.2032 0.3048)
						)
						(arc
							(start 0.2032 0.3048)
							(mid 0.275042 0.275042)
							(end 0.3048 0.2032)
						)
					)
					(width 0)
					(fill yes)
				)
			)
		)
	)
	(footprint ""
		(layer "F.Cu")
		(at 111.51997 -78.7146)
		(property "Reference" "STP67"
			(at 0 0 0)
			(layer "F.SilkS")
			(hide yes)
			(effects
				(font
					(size 1.27 1.27)
				)
			)
		)
		(property "Value" "TPAD28"
			(at 0.0127 -1.8034 0)
			(unlocked yes)
			(layer "F.Fab")
			(hide yes)
			(effects
				(font
					(size 1.016 1.016)
					(thickness 0.1524)
				)
			)
		)
		(property "Device Type" "TPAD28"
			(at 0.0127 -3.3274 0)
			(unlocked yes)
			(layer "F.Fab")
			(hide yes)
			(effects
				(font
					(size 1.016 1.016)
					(thickness 0.1524)
				)
			)
		)
		(duplicate_pad_numbers_are_jumpers no)
		(fp_poly
			(pts
				(arc
					(start 0.3556 0)
					(mid -0.3556 0)
					(end 0.3556 0)
				)
			)
			(stroke
				(width 0)
				(type default)
			)
			(fill no)
			(layer "F.CrtYd")
		)
		(fp_poly
			(pts
				(arc
					(start 0.6096 0)
					(mid -0.6096 0)
					(end 0.6096 0)
				)
			)
			(stroke
				(width 0)
				(type default)
			)
			(fill no)
			(layer "F.Fab")
		)
		(pad "1" smd circle
			(at 0 0)
			(size 0.7112 0.7112)
			(layers "F.Cu" "F.Mask" "F.Paste")
			(net "EXP_TEST_MUX29")
		)
	)
	(footprint ""
		(layer "F.Cu")
		(at 318.008 -164.338 -90)
		(property "Reference" "R263"
			(at 0 0 270)
			(layer "F.SilkS")
			(hide yes)
			(effects
				(font
					(size 1.27 1.27)
				)
			)
		)
		(property "Value" "10KR2F-2-GP"
			(at 0.064008 -3.993896 270)
			(unlocked yes)
			(layer "F.Fab")
			(hide yes)
			(effects
				(font
					(size 1.016 1.016)
					(thickness 0.1524)
				)
			)
		)
		(property "Device Type" "R402H16"
			(at 0.064008 -5.517896 270)
			(unlocked yes)
			(layer "F.Fab")
			(hide yes)
			(effects
				(font
					(size 1.016 1.016)
					(thickness 0.1524)
				)
			)
		)
		(duplicate_pad_numbers_are_jumpers no)
		(fp_line
			(start -0.508 -0.9398)
			(end -0.508 0.9398)
			(stroke
				(width 0.1524)
				(type default)
			)
			(layer "F.SilkS")
		)
		(fp_line
			(start 0.508 -0.9398)
			(end -0.508 -0.9398)
			(stroke
				(width 0.1524)
				(type default)
			)
			(layer "F.SilkS")
		)
		(fp_rect
			(start -0.508 0.9398)
			(end 0.508 -0.9398)
			(stroke
				(width 0)
				(type default)
			)
			(fill no)
			(layer "F.CrtYd")
		)
		(fp_rect
			(start -0.508 0.9398)
			(end 0.508 -0.9398)
			(stroke
				(width 0)
				(type default)
			)
			(fill no)
			(layer "F.Fab")
		)
		(pad "1" smd custom
			(at 0 -0.4445 270)
			(size 0.1397 0.1397)
			(layers "F.Cu" "F.Mask" "F.Paste")
			(net "P3V3_STBY")
			(options
				(clearance outline)
				(anchor circle)
			)
			(primitives
				(gr_poly
					(pts
						(arc
							(start -0.1778 -0.2794)
							(mid -0.249642 -0.249642)
							(end -0.2794 -0.1778)
						)
						(arc
							(start -0.2794 0.1778)
							(mid -0.249642 0.249642)
							(end -0.1778 0.2794)
						)
						(arc
							(start 0.1778 0.2794)
							(mid 0.249642 0.249642)
							(end 0.2794 0.1778)
						)
						(arc
							(start 0.2794 -0.1778)
							(mid 0.249642 -0.249642)
							(end 0.1778 -0.2794)
						)
					)
					(width 0)
					(fill yes)
				)
			)
		)
		(pad "2" smd custom
			(at 0 0.4445 270)
			(size 0.1397 0.1397)
			(layers "F.Cu" "F.Mask" "F.Paste")
			(net "PU_BMC0_SDA12")
			(options
				(clearance outline)
				(anchor circle)
			)
			(primitives
				(gr_poly
					(pts
						(arc
							(start -0.1778 -0.2794)
							(mid -0.249642 -0.249642)
							(end -0.2794 -0.1778)
						)
						(arc
							(start -0.2794 0.1778)
							(mid -0.249642 0.249642)
							(end -0.1778 0.2794)
						)
						(arc
							(start 0.1778 0.2794)
							(mid 0.249642 0.249642)
							(end 0.2794 0.1778)
						)
						(arc
							(start 0.2794 -0.1778)
							(mid 0.249642 -0.249642)
							(end 0.1778 -0.2794)
						)
					)
					(width 0)
					(fill yes)
				)
			)
		)
	)
	(footprint ""
		(layer "F.Cu")
		(at 254.762 -136.779)
		(property "Reference" "R7907"
			(at 0 0 0)
			(layer "F.SilkS")
			(hide yes)
			(effects
				(font
					(size 1.27 1.27)
				)
			)
		)
		(property "Value" "0R2J-2-GP"
			(at 0.064008 -3.993896 0)
			(unlocked yes)
			(layer "F.Fab")
			(hide yes)
			(effects
				(font
					(size 1.016 1.016)
					(thickness 0.1524)
				)
			)
		)
		(property "Device Type" "R402H16"
			(at 0.064008 -5.517896 0)
			(unlocked yes)
			(layer "F.Fab")
			(hide yes)
			(effects
				(font
					(size 1.016 1.016)
					(thickness 0.1524)
				)
			)
		)
		(duplicate_pad_numbers_are_jumpers no)
		(fp_line
			(start -0.508 -0.9398)
			(end -0.508 0.9398)
			(stroke
				(width 0.1524)
				(type default)
			)
			(layer "F.SilkS")
		)
		(fp_line
			(start 0.508 -0.9398)
			(end -0.508 -0.9398)
			(stroke
				(width 0.1524)
				(type default)
			)
			(layer "F.SilkS")
		)
		(fp_rect
			(start -0.508 0.9398)
			(end 0.508 -0.9398)
			(stroke
				(width 0)
				(type default)
			)
			(fill no)
			(layer "F.CrtYd")
		)
		(fp_rect
			(start -0.508 0.9398)
			(end 0.508 -0.9398)
			(stroke
				(width 0)
				(type default)
			)
			(fill no)
			(layer "F.Fab")
		)
		(pad "1" smd custom
			(at 0 -0.4445)
			(size 0.1397 0.1397)
			(layers "F.Cu" "F.Mask" "F.Paste")
			(net "CPU_BMC_UART_TX")
			(options
				(clearance outline)
				(anchor circle)
			)
			(primitives
				(gr_poly
					(pts
						(arc
							(start -0.1778 -0.2794)
							(mid -0.249642 -0.249642)
							(end -0.2794 -0.1778)
						)
						(arc
							(start -0.2794 0.1778)
							(mid -0.249642 0.249642)
							(end -0.1778 0.2794)
						)
						(arc
							(start 0.1778 0.2794)
							(mid 0.249642 0.249642)
							(end 0.2794 0.1778)
						)
						(arc
							(start 0.2794 -0.1778)
							(mid 0.249642 -0.249642)
							(end 0.1778 -0.2794)
						)
					)
					(width 0)
					(fill yes)
				)
			)
		)
		(pad "2" smd custom
			(at 0 0.4445)
			(size 0.1397 0.1397)
			(layers "F.Cu" "F.Mask" "F.Paste")
			(net "CPU_U193_PIN5_TX")
			(options
				(clearance outline)
				(anchor circle)
			)
			(primitives
				(gr_poly
					(pts
						(arc
							(start -0.1778 -0.2794)
							(mid -0.249642 -0.249642)
							(end -0.2794 -0.1778)
						)
						(arc
							(start -0.2794 0.1778)
							(mid -0.249642 0.249642)
							(end -0.1778 0.2794)
						)
						(arc
							(start 0.1778 0.2794)
							(mid 0.249642 0.249642)
							(end 0.2794 0.1778)
						)
						(arc
							(start 0.2794 -0.1778)
							(mid 0.249642 -0.249642)
							(end 0.1778 -0.2794)
						)
					)
					(width 0)
					(fill yes)
				)
			)
		)
	)
	(footprint ""
		(layer "F.Cu")
		(at 134.50697 -98.806 180)
		(property "Reference" "SC1269"
			(at 0 0 180)
			(layer "F.SilkS")
			(hide yes)
			(effects
				(font
					(size 1.27 1.27)
				)
			)
		)
		(property "Value" "SCD01U10V1KX-GP"
			(at -2.8321 -1.7399 180)
			(unlocked yes)
			(layer "F.Fab")
			(hide yes)
			(effects
				(font
					(size 1.016 1.016)
					(thickness 0.1524)
				)
			)
		)
		(property "Device Type" "C0201H13"
			(at -2.8321 -3.2639 180)
			(unlocked yes)
			(layer "F.Fab")
			(hide yes)
			(effects
				(font
					(size 1.016 1.016)
					(thickness 0.1524)
				)
			)
		)
		(duplicate_pad_numbers_are_jumpers no)
		(fp_rect
			(start -0.2794 0.6477)
			(end 0.2794 -0.6477)
			(stroke
				(width 0)
				(type default)
			)
			(fill no)
			(layer "F.CrtYd")
		)
		(fp_rect
			(start -0.2794 0.6477)
			(end 0.2794 -0.6477)
			(stroke
				(width 0)
				(type default)
			)
			(fill no)
			(layer "F.Fab")
		)
		(pad "1" smd custom
			(at 0 -0.2794 180)
			(size 0.0762 0.0762)
			(layers "F.Cu" "F.Mask" "F.Paste")
			(net "3X24_SAS_TX21_N")
			(options
				(clearance outline)
				(anchor circle)
			)
			(primitives
				(gr_poly
					(pts
						(arc
							(start 0.1524 -0.127)
							(mid 0.137521 -0.162921)
							(end 0.1016 -0.1778)
						)
						(arc
							(start -0.1016 -0.1778)
							(mid -0.137521 -0.162921)
							(end -0.1524 -0.127)
						)
						(arc
							(start -0.1524 0.127)
							(mid -0.137521 0.162921)
							(end -0.1016 0.1778)
						)
						(arc
							(start 0.1016 0.1778)
							(mid 0.137521 0.162921)
							(end 0.1524 0.127)
						)
					)
					(width 0)
					(fill yes)
				)
			)
		)
		(pad "2" smd custom
			(at 0 0.2794 180)
			(size 0.0762 0.0762)
			(layers "F.Cu" "F.Mask" "F.Paste")
			(net "SAS_EXP_GF_TX_DN1")
			(options
				(clearance outline)
				(anchor circle)
			)
			(primitives
				(gr_poly
					(pts
						(arc
							(start 0.1524 -0.127)
							(mid 0.137521 -0.162921)
							(end 0.1016 -0.1778)
						)
						(arc
							(start -0.1016 -0.1778)
							(mid -0.137521 -0.162921)
							(end -0.1524 -0.127)
						)
						(arc
							(start -0.1524 0.127)
							(mid -0.137521 0.162921)
							(end -0.1016 0.1778)
						)
						(arc
							(start 0.1016 0.1778)
							(mid 0.137521 0.162921)
							(end 0.1524 0.127)
						)
					)
					(width 0)
					(fill yes)
				)
			)
		)
	)
	(footprint ""
		(layer "F.Cu")
		(at 198.755 -97.917 -90)
		(property "Reference" "PC238"
			(at 0 0 270)
			(layer "F.SilkS")
			(hide yes)
			(effects
				(font
					(size 1.27 1.27)
				)
			)
		)
		(property "Value" "SC47U6D3V5MX-1-GP"
			(at -0.0762 -6.1214 270)
			(unlocked yes)
			(layer "F.Fab")
			(hide yes)
			(effects
				(font
					(size 1.016 1.016)
					(thickness 0.1524)
				)
			)
		)
		(property "Device Type" "C805H54"
			(at -0.0762 -8.1534 270)
			(unlocked yes)
			(layer "F.Fab")
			(hide yes)
			(effects
				(font
					(size 1.016 1.016)
					(thickness 0.1524)
				)
			)
		)
		(duplicate_pad_numbers_are_jumpers no)
		(fp_line
			(start 0.635 0)
			(end -0.635 0)
			(stroke
				(width 0.508)
				(type default)
			)
			(layer "F.SilkS")
		)
		(fp_rect
			(start -0.9652 1.778)
			(end 0.9652 -1.778)
			(stroke
				(width 0)
				(type default)
			)
			(fill no)
			(layer "F.CrtYd")
		)
		(fp_poly
			(pts
				(xy -0.9652 -1.778) (xy 0.9652 -1.778) (xy 0.9652 1.778) (xy -0.9652 1.778)
			)
			(stroke
				(width 0)
				(type default)
			)
			(fill no)
			(layer "F.Fab")
		)
		(pad "1" smd rect
			(at 0 -0.9652 270)
			(size 1.397 1.143)
			(layers "F.Cu" "F.Mask" "F.Paste")
			(net "P1V5_E")
		)
		(pad "2" smd rect
			(at 0 0.9652 270)
			(size 1.397 1.143)
			(layers "F.Cu" "F.Mask" "F.Paste")
			(net "GND")
		)
	)
	(footprint ""
		(layer "F.Cu")
		(at 268.351 -218.059 90)
		(property "Reference" "PC96"
			(at 0 0 90)
			(layer "F.SilkS")
			(hide yes)
			(effects
				(font
					(size 1.27 1.27)
				)
			)
		)
		(property "Value" "SC10U6D3V5KX-1GP"
			(at -0.0762 -6.1214 90)
			(unlocked yes)
			(layer "F.Fab")
			(hide yes)
			(effects
				(font
					(size 1.016 1.016)
					(thickness 0.1524)
				)
			)
		)
		(property "Device Type" "C805H54"
			(at -0.0762 -8.1534 90)
			(unlocked yes)
			(layer "F.Fab")
			(hide yes)
			(effects
				(font
					(size 1.016 1.016)
					(thickness 0.1524)
				)
			)
		)
		(duplicate_pad_numbers_are_jumpers no)
		(fp_line
			(start 0.635 0)
			(end -0.635 0)
			(stroke
				(width 0.508)
				(type default)
			)
			(layer "F.SilkS")
		)
		(fp_rect
			(start -0.9652 1.778)
			(end 0.9652 -1.778)
			(stroke
				(width 0)
				(type default)
			)
			(fill no)
			(layer "F.CrtYd")
		)
		(fp_poly
			(pts
				(xy -0.9652 -1.778) (xy 0.9652 -1.778) (xy 0.9652 1.778) (xy -0.9652 1.778)
			)
			(stroke
				(width 0)
				(type default)
			)
			(fill no)
			(layer "F.Fab")
		)
		(pad "1" smd rect
			(at 0 -0.9652 90)
			(size 1.397 1.143)
			(layers "F.Cu" "F.Mask" "F.Paste")
			(net "TPS74801_1V26_STBY_OUT")
		)
		(pad "2" smd rect
			(at 0 0.9652 90)
			(size 1.397 1.143)
			(layers "F.Cu" "F.Mask" "F.Paste")
			(net "GND")
		)
	)
	(footprint ""
		(layer "F.Cu")
		(at 311.531 -110.236)
		(property "Reference" "PC33"
			(at 0 0 0)
			(layer "F.SilkS")
			(hide yes)
			(effects
				(font
					(size 1.27 1.27)
				)
			)
		)
		(property "Value" "SC1U10V2KX-1GP"
			(at 1.1811 -2.7051 0)
			(unlocked yes)
			(layer "F.Fab")
			(hide yes)
			(effects
				(font
					(size 1.016 1.016)
					(thickness 0.1524)
				)
			)
		)
		(property "Device Type" "C402H22"
			(at 1.1811 -4.2291 0)
			(unlocked yes)
			(layer "F.Fab")
			(hide yes)
			(effects
				(font
					(size 1.016 1.016)
					(thickness 0.1524)
				)
			)
		)
		(duplicate_pad_numbers_are_jumpers no)
		(fp_rect
			(start -0.4318 0.9525)
			(end 0.4318 -0.9525)
			(stroke
				(width 0)
				(type default)
			)
			(fill no)
			(layer "F.CrtYd")
		)
		(fp_rect
			(start -0.4318 0.9525)
			(end 0.4318 -0.9525)
			(stroke
				(width 0)
				(type default)
			)
			(fill no)
			(layer "F.Fab")
		)
		(pad "1" smd custom
			(at 0 -0.4445)
			(size 0.1524 0.1524)
			(layers "F.Cu" "F.Mask" "F.Paste")
			(net "AGND_P3V3_STBY")
			(options
				(clearance outline)
				(anchor circle)
			)
			(primitives
				(gr_poly
					(pts
						(arc
							(start 0.3048 -0.2032)
							(mid 0.275042 -0.275042)
							(end 0.2032 -0.3048)
						)
						(arc
							(start -0.2032 -0.3048)
							(mid -0.275042 -0.275042)
							(end -0.3048 -0.2032)
						)
						(arc
							(start -0.3048 0.2032)
							(mid -0.275042 0.275042)
							(end -0.2032 0.3048)
						)
						(arc
							(start 0.2032 0.3048)
							(mid 0.275042 0.275042)
							(end 0.3048 0.2032)
						)
					)
					(width 0)
					(fill yes)
				)
			)
		)
		(pad "2" smd custom
			(at 0 0.4445)
			(size 0.1524 0.1524)
			(layers "F.Cu" "F.Mask" "F.Paste")
			(net "P3V3_STBY_ROVP")
			(options
				(clearance outline)
				(anchor circle)
			)
			(primitives
				(gr_poly
					(pts
						(arc
							(start 0.3048 -0.2032)
							(mid 0.275042 -0.275042)
							(end 0.2032 -0.3048)
						)
						(arc
							(start -0.2032 -0.3048)
							(mid -0.275042 -0.275042)
							(end -0.3048 -0.2032)
						)
						(arc
							(start -0.3048 0.2032)
							(mid -0.275042 0.275042)
							(end -0.2032 0.3048)
						)
						(arc
							(start 0.2032 0.3048)
							(mid 0.275042 0.275042)
							(end 0.3048 0.2032)
						)
					)
					(width 0)
					(fill yes)
				)
			)
		)
	)
)
